(kicad_pcb
	(version 20260206)
	(generator "pcbnew")
	(generator_version "10.0")
	(general
		(thickness 1.6)
		(legacy_teardrops no)
	)
	(paper "A4")
	(title_block
		(title "baseboard — 13948-1b.1110WZS1818.brd")
		(comment 1 "Honey Badger (Wiwynn) / footprints 1313-1320 of 2523")
	)
	(layers
		(0 "F.Cu" signal "TOP")
		(4 "In1.Cu" signal "L2GND")
		(6 "In2.Cu" signal "L3")
		(8 "In3.Cu" signal "L4VCC")
		(10 "In4.Cu" signal "L5VCC")
		(12 "In5.Cu" signal "L6")
		(14 "In6.Cu" signal "L7GND")
		(2 "B.Cu" signal "BOTTOM")
		(9 "F.Adhes" user "F.Adhesive")
		(11 "B.Adhes" user "B.Adhesive")
		(13 "F.Paste" user "Package Geometry/Pastemask Top")
		(15 "B.Paste" user "Package Geometry/Pastemask Bottom")
		(5 "F.SilkS" user "Ref Des/Silkscreen Top")
		(7 "B.SilkS" user "Ref Des/Silkscreen Bottom")
		(1 "F.Mask" user "Board Geometry/Soldermask Top")
		(3 "B.Mask" user "Board Geometry/Soldermask Bottom")
		(17 "Dwgs.User" user "User.Drawings")
		(19 "Cmts.User" user "User.Comments")
		(21 "Eco1.User" user "User.Eco1")
		(23 "Eco2.User" user "User.Eco2")
		(25 "Edge.Cuts" user "Board Geometry/Outline")
		(27 "Margin" user)
		(31 "F.CrtYd" user "Package Geometry/Place Bound Top")
		(29 "B.CrtYd" user "Package Geometry/Place Bound Bottom")
		(35 "F.Fab" user "Ref Des/Assembly Top")
		(33 "B.Fab" user "Ref Des/Assembly Bottom")
	)
	(footprint ""
		(layer "F.Cu")
		(at 264.033 -31.496 90)
		(property "Reference" "PC53"
			(at 0 0 90)
			(layer "F.SilkS")
			(hide yes)
			(effects
				(font
					(size 1.27 1.27)
				)
			)
		)
		(property "Value" "SC1U10V2KX-1GP"
			(at 1.1811 -2.7051 90)
			(unlocked yes)
			(layer "F.Fab")
			(hide yes)
			(effects
				(font
					(size 1.016 1.016)
					(thickness 0.1524)
				)
			)
		)
		(property "Device Type" "C402H22"
			(at 1.1811 -4.2291 90)
			(unlocked yes)
			(layer "F.Fab")
			(hide yes)
			(effects
				(font
					(size 1.016 1.016)
					(thickness 0.1524)
				)
			)
		)
		(duplicate_pad_numbers_are_jumpers no)
		(fp_rect
			(start -0.4318 0.9525)
			(end 0.4318 -0.9525)
			(stroke
				(width 0)
				(type default)
			)
			(fill no)
			(layer "F.CrtYd")
		)
		(fp_rect
			(start -0.4318 0.9525)
			(end 0.4318 -0.9525)
			(stroke
				(width 0)
				(type default)
			)
			(fill no)
			(layer "F.Fab")
		)
		(pad "1" smd custom
			(at 0 -0.4445 90)
			(size 0.1524 0.1524)
			(layers "F.Cu" "F.Mask" "F.Paste")
			(net "AGND_P1V8_STBY")
			(options
				(clearance outline)
				(anchor circle)
			)
			(primitives
				(gr_poly
					(pts
						(arc
							(start 0.3048 -0.2032)
							(mid 0.275042 -0.275042)
							(end 0.2032 -0.3048)
						)
						(arc
							(start -0.2032 -0.3048)
							(mid -0.275042 -0.275042)
							(end -0.3048 -0.2032)
						)
						(arc
							(start -0.3048 0.2032)
							(mid -0.275042 0.275042)
							(end -0.2032 0.3048)
						)
						(arc
							(start 0.2032 0.3048)
							(mid 0.275042 0.275042)
							(end 0.3048 0.2032)
						)
					)
					(width 0)
					(fill yes)
				)
			)
		)
		(pad "2" smd custom
			(at 0 0.4445 90)
			(size 0.1524 0.1524)
			(layers "F.Cu" "F.Mask" "F.Paste")
			(net "P1V8_STBY_ROVP")
			(options
				(clearance outline)
				(anchor circle)
			)
			(primitives
				(gr_poly
					(pts
						(arc
							(start 0.3048 -0.2032)
							(mid 0.275042 -0.275042)
							(end 0.2032 -0.3048)
						)
						(arc
							(start -0.2032 -0.3048)
							(mid -0.275042 -0.275042)
							(end -0.3048 -0.2032)
						)
						(arc
							(start -0.3048 0.2032)
							(mid -0.275042 0.275042)
							(end -0.2032 0.3048)
						)
						(arc
							(start 0.2032 0.3048)
							(mid 0.275042 0.275042)
							(end 0.3048 0.2032)
						)
					)
					(width 0)
					(fill yes)
				)
			)
		)
	)
	(footprint ""
		(layer "F.Cu")
		(at 223.139 -161.671 90)
		(property "Reference" "C88"
			(at 0 0 90)
			(layer "F.SilkS")
			(hide yes)
			(effects
				(font
					(size 1.27 1.27)
				)
			)
		)
		(property "Value" "SCD1U16V2KX-3GP"
			(at 1.1811 -2.7051 90)
			(unlocked yes)
			(layer "F.Fab")
			(hide yes)
			(effects
				(font
					(size 1.016 1.016)
					(thickness 0.1524)
				)
			)
		)
		(property "Device Type" "C402H22"
			(at 1.1811 -4.2291 90)
			(unlocked yes)
			(layer "F.Fab")
			(hide yes)
			(effects
				(font
					(size 1.016 1.016)
					(thickness 0.1524)
				)
			)
		)
		(duplicate_pad_numbers_are_jumpers no)
		(fp_rect
			(start -0.4318 0.9525)
			(end 0.4318 -0.9525)
			(stroke
				(width 0)
				(type default)
			)
			(fill no)
			(layer "F.CrtYd")
		)
		(fp_rect
			(start -0.4318 0.9525)
			(end 0.4318 -0.9525)
			(stroke
				(width 0)
				(type default)
			)
			(fill no)
			(layer "F.Fab")
		)
		(pad "1" smd custom
			(at 0 -0.4445 90)
			(size 0.1524 0.1524)
			(layers "F.Cu" "F.Mask" "F.Paste")
			(net "P3V3_STBY")
			(options
				(clearance outline)
				(anchor circle)
			)
			(primitives
				(gr_poly
					(pts
						(arc
							(start 0.3048 -0.2032)
							(mid 0.275042 -0.275042)
							(end 0.2032 -0.3048)
						)
						(arc
							(start -0.2032 -0.3048)
							(mid -0.275042 -0.275042)
							(end -0.3048 -0.2032)
						)
						(arc
							(start -0.3048 0.2032)
							(mid -0.275042 0.275042)
							(end -0.2032 0.3048)
						)
						(arc
							(start 0.2032 0.3048)
							(mid 0.275042 0.275042)
							(end 0.3048 0.2032)
						)
					)
					(width 0)
					(fill yes)
				)
			)
		)
		(pad "2" smd custom
			(at 0 0.4445 90)
			(size 0.1524 0.1524)
			(layers "F.Cu" "F.Mask" "F.Paste")
			(net "GND")
			(options
				(clearance outline)
				(anchor circle)
			)
			(primitives
				(gr_poly
					(pts
						(arc
							(start 0.3048 -0.2032)
							(mid 0.275042 -0.275042)
							(end 0.2032 -0.3048)
						)
						(arc
							(start -0.2032 -0.3048)
							(mid -0.275042 -0.275042)
							(end -0.3048 -0.2032)
						)
						(arc
							(start -0.3048 0.2032)
							(mid -0.275042 0.275042)
							(end -0.2032 0.3048)
						)
						(arc
							(start 0.2032 0.3048)
							(mid 0.275042 0.275042)
							(end 0.3048 0.2032)
						)
					)
					(width 0)
					(fill yes)
				)
			)
		)
	)
	(footprint ""
		(layer "F.Cu")
		(at 131.069842 -85.034882 90)
		(property "Reference" "SC1261"
			(at 0 0 90)
			(layer "F.SilkS")
			(hide yes)
			(effects
				(font
					(size 1.27 1.27)
				)
			)
		)
		(property "Value" "SCD01U10V1KX-GP"
			(at -2.8321 -1.7399 90)
			(unlocked yes)
			(layer "F.Fab")
			(hide yes)
			(effects
				(font
					(size 1.016 1.016)
					(thickness 0.1524)
				)
			)
		)
		(property "Device Type" "C0201H13"
			(at -2.8321 -3.2639 90)
			(unlocked yes)
			(layer "F.Fab")
			(hide yes)
			(effects
				(font
					(size 1.016 1.016)
					(thickness 0.1524)
				)
			)
		)
		(duplicate_pad_numbers_are_jumpers no)
		(fp_rect
			(start -0.2794 0.6477)
			(end 0.2794 -0.6477)
			(stroke
				(width 0)
				(type default)
			)
			(fill no)
			(layer "F.CrtYd")
		)
		(fp_rect
			(start -0.2794 0.6477)
			(end 0.2794 -0.6477)
			(stroke
				(width 0)
				(type default)
			)
			(fill no)
			(layer "F.Fab")
		)
		(pad "1" smd custom
			(at 0 -0.2794 90)
			(size 0.0762 0.0762)
			(layers "F.Cu" "F.Mask" "F.Paste")
			(net "SAS_HDD_TX15_P")
			(options
				(clearance outline)
				(anchor circle)
			)
			(primitives
				(gr_poly
					(pts
						(arc
							(start 0.1524 -0.127)
							(mid 0.137521 -0.162921)
							(end 0.1016 -0.1778)
						)
						(arc
							(start -0.1016 -0.1778)
							(mid -0.137521 -0.162921)
							(end -0.1524 -0.127)
						)
						(arc
							(start -0.1524 0.127)
							(mid -0.137521 0.162921)
							(end -0.1016 0.1778)
						)
						(arc
							(start 0.1016 0.1778)
							(mid 0.137521 0.162921)
							(end 0.1524 0.127)
						)
					)
					(width 0)
					(fill yes)
				)
			)
		)
		(pad "2" smd custom
			(at 0 0.2794 90)
			(size 0.0762 0.0762)
			(layers "F.Cu" "F.Mask" "F.Paste")
			(net "3008_SAS_RX_P3")
			(options
				(clearance outline)
				(anchor circle)
			)
			(primitives
				(gr_poly
					(pts
						(arc
							(start 0.1524 -0.127)
							(mid 0.137521 -0.162921)
							(end 0.1016 -0.1778)
						)
						(arc
							(start -0.1016 -0.1778)
							(mid -0.137521 -0.162921)
							(end -0.1524 -0.127)
						)
						(arc
							(start -0.1524 0.127)
							(mid -0.137521 0.162921)
							(end -0.1016 0.1778)
						)
						(arc
							(start 0.1016 0.1778)
							(mid 0.137521 0.162921)
							(end 0.1524 0.127)
						)
					)
					(width 0)
					(fill yes)
				)
			)
		)
	)
	(footprint ""
		(layer "F.Cu")
		(at 111.76 -29.21)
		(property "Reference" "STP40"
			(at 0 0 0)
			(layer "F.SilkS")
			(hide yes)
			(effects
				(font
					(size 1.27 1.27)
				)
			)
		)
		(property "Value" "TPAD28"
			(at 0.0127 -1.8034 0)
			(unlocked yes)
			(layer "F.Fab")
			(hide yes)
			(effects
				(font
					(size 1.016 1.016)
					(thickness 0.1524)
				)
			)
		)
		(property "Device Type" "TPAD28"
			(at 0.0127 -3.3274 0)
			(unlocked yes)
			(layer "F.Fab")
			(hide yes)
			(effects
				(font
					(size 1.016 1.016)
					(thickness 0.1524)
				)
			)
		)
		(duplicate_pad_numbers_are_jumpers no)
		(fp_poly
			(pts
				(arc
					(start 0.3556 0)
					(mid -0.3556 0)
					(end 0.3556 0)
				)
			)
			(stroke
				(width 0)
				(type default)
			)
			(fill no)
			(layer "F.CrtYd")
		)
		(fp_poly
			(pts
				(arc
					(start 0.6096 0)
					(mid -0.6096 0)
					(end 0.6096 0)
				)
			)
			(stroke
				(width 0)
				(type default)
			)
			(fill no)
			(layer "F.Fab")
		)
		(pad "1" smd circle
			(at 0 0)
			(size 0.7112 0.7112)
			(layers "F.Cu" "F.Mask" "F.Paste")
			(net "SYS_HALT0#")
		)
	)
	(footprint ""
		(layer "F.Cu")
		(at 240.053876 -13.156438 90)
		(property "Reference" "R305"
			(at 0 0 90)
			(layer "F.SilkS")
			(hide yes)
			(effects
				(font
					(size 1.27 1.27)
				)
			)
		)
		(property "Value" "0R2J-2-GP"
			(at 0.064008 -3.993896 90)
			(unlocked yes)
			(layer "F.Fab")
			(hide yes)
			(effects
				(font
					(size 1.016 1.016)
					(thickness 0.1524)
				)
			)
		)
		(property "Device Type" "R402H16"
			(at 0.064008 -5.517896 90)
			(unlocked yes)
			(layer "F.Fab")
			(hide yes)
			(effects
				(font
					(size 1.016 1.016)
					(thickness 0.1524)
				)
			)
		)
		(duplicate_pad_numbers_are_jumpers no)
		(fp_line
			(start 0.508 -0.9398)
			(end -0.508 -0.9398)
			(stroke
				(width 0.1524)
				(type default)
			)
			(layer "F.SilkS")
		)
		(fp_line
			(start -0.508 -0.9398)
			(end -0.508 0.9398)
			(stroke
				(width 0.1524)
				(type default)
			)
			(layer "F.SilkS")
		)
		(fp_rect
			(start -0.508 0.9398)
			(end 0.508 -0.9398)
			(stroke
				(width 0)
				(type default)
			)
			(fill no)
			(layer "F.CrtYd")
		)
		(fp_rect
			(start -0.508 0.9398)
			(end 0.508 -0.9398)
			(stroke
				(width 0)
				(type default)
			)
			(fill no)
			(layer "F.Fab")
		)
		(pad "1" smd custom
			(at 0 -0.4445 90)
			(size 0.1397 0.1397)
			(layers "F.Cu" "F.Mask" "F.Paste")
			(net "HB_OUT_R")
			(options
				(clearance outline)
				(anchor circle)
			)
			(primitives
				(gr_poly
					(pts
						(arc
							(start -0.1778 -0.2794)
							(mid -0.249642 -0.249642)
							(end -0.2794 -0.1778)
						)
						(arc
							(start -0.2794 0.1778)
							(mid -0.249642 0.249642)
							(end -0.1778 0.2794)
						)
						(arc
							(start 0.1778 0.2794)
							(mid 0.249642 0.249642)
							(end 0.2794 0.1778)
						)
						(arc
							(start 0.2794 -0.1778)
							(mid 0.249642 -0.249642)
							(end 0.1778 -0.2794)
						)
					)
					(width 0)
					(fill yes)
				)
			)
		)
		(pad "2" smd custom
			(at 0 0.4445 90)
			(size 0.1397 0.1397)
			(layers "F.Cu" "F.Mask" "F.Paste")
			(net "HB_OUT")
			(options
				(clearance outline)
				(anchor circle)
			)
			(primitives
				(gr_poly
					(pts
						(arc
							(start -0.1778 -0.2794)
							(mid -0.249642 -0.249642)
							(end -0.2794 -0.1778)
						)
						(arc
							(start -0.2794 0.1778)
							(mid -0.249642 0.249642)
							(end -0.1778 0.2794)
						)
						(arc
							(start 0.1778 0.2794)
							(mid 0.249642 0.249642)
							(end 0.2794 0.1778)
						)
						(arc
							(start 0.2794 -0.1778)
							(mid 0.249642 -0.249642)
							(end 0.1778 -0.2794)
						)
					)
					(width 0)
					(fill yes)
				)
			)
		)
	)
	(footprint ""
		(layer "F.Cu")
		(at 306.959 -180.467)
		(property "Reference" "TP102"
			(at 0 0 0)
			(layer "F.SilkS")
			(hide yes)
			(effects
				(font
					(size 1.27 1.27)
				)
			)
		)
		(property "Value" "TPAD28"
			(at 0.0127 -1.8034 0)
			(unlocked yes)
			(layer "F.Fab")
			(hide yes)
			(effects
				(font
					(size 1.016 1.016)
					(thickness 0.1524)
				)
			)
		)
		(property "Device Type" "TPAD28"
			(at 0.0127 -3.3274 0)
			(unlocked yes)
			(layer "F.Fab")
			(hide yes)
			(effects
				(font
					(size 1.016 1.016)
					(thickness 0.1524)
				)
			)
		)
		(duplicate_pad_numbers_are_jumpers no)
		(fp_poly
			(pts
				(arc
					(start 0.3556 0)
					(mid -0.3556 0)
					(end 0.3556 0)
				)
			)
			(stroke
				(width 0)
				(type default)
			)
			(fill no)
			(layer "F.CrtYd")
		)
		(fp_poly
			(pts
				(arc
					(start 0.6096 0)
					(mid -0.6096 0)
					(end 0.6096 0)
				)
			)
			(stroke
				(width 0)
				(type default)
			)
			(fill no)
			(layer "F.Fab")
		)
		(pad "1" smd circle
			(at 0 0)
			(size 0.7112 0.7112)
			(layers "F.Cu" "F.Mask" "F.Paste")
			(net "TP_BMC_GPIOL5")
		)
	)
	(footprint ""
		(layer "F.Cu")
		(at 220.472 -185.547 180)
		(property "Reference" "U36"
			(at 0 0 180)
			(layer "F.SilkS")
			(hide yes)
			(effects
				(font
					(size 1.27 1.27)
				)
			)
		)
		(property "Value" "LM393ADR-1-GP"
			(at -3.707384 -1.5367 180)
			(unlocked yes)
			(layer "F.Fab")
			(hide yes)
			(effects
				(font
					(size 1.016 1.016)
					(thickness 0.1524)
				)
			)
		)
		(property "Device Type" "SOIC8H69"
			(at -3.707384 -3.0607 180)
			(unlocked yes)
			(layer "F.Fab")
			(hide yes)
			(effects
				(font
					(size 1.016 1.016)
					(thickness 0.1524)
				)
			)
		)
		(duplicate_pad_numbers_are_jumpers no)
		(fp_line
			(start 2.1336 1.4224)
			(end 2.1336 -1.4224)
			(stroke
				(width 0.1524)
				(type default)
			)
			(layer "F.SilkS")
		)
		(fp_line
			(start 2.1336 -1.4224)
			(end -2.7432 -1.4224)
			(stroke
				(width 0.1524)
				(type default)
			)
			(layer "F.SilkS")
		)
		(fp_line
			(start -2.1844 -0.0508)
			(end -2.7178 0.508)
			(stroke
				(width 0.1524)
				(type default)
			)
			(layer "F.SilkS")
		)
		(fp_line
			(start -2.6289 3.4417)
			(end -2.6289 1.4732)
			(stroke
				(width 0.381)
				(type default)
			)
			(layer "F.SilkS")
		)
		(fp_line
			(start -2.7178 -0.508)
			(end -2.1844 -0.0508)
			(stroke
				(width 0.1524)
				(type default)
			)
			(layer "F.SilkS")
		)
		(fp_line
			(start -2.7432 1.4224)
			(end 2.1336 1.4224)
			(stroke
				(width 0.1524)
				(type default)
			)
			(layer "F.SilkS")
		)
		(fp_line
			(start -2.7432 1.4224)
			(end -2.6416 1.4224)
			(stroke
				(width 0.1524)
				(type default)
			)
			(layer "F.SilkS")
		)
		(fp_line
			(start -2.7432 -1.4224)
			(end -2.7432 1.4224)
			(stroke
				(width 0.1524)
				(type default)
			)
			(layer "F.SilkS")
		)
		(fp_poly
			(pts
				(xy -2.2098 -1.4224) (xy -2.2098 1.4224) (xy 2.2098 1.4224) (xy 2.2098 -1.4224)
			)
			(stroke
				(width 0)
				(type default)
			)
			(fill yes)
			(layer "F.SilkS")
		)
		(fp_rect
			(start -2.450084 2.999994)
			(end 2.450084 -2.999994)
			(stroke
				(width 0)
				(type default)
			)
			(fill no)
			(layer "F.CrtYd")
		)
		(fp_poly
			(pts
				(xy -2.8194 3.6322) (xy -2.8194 -3.6322) (xy 2.8194 -3.6322) (xy 2.8194 1.18364) (xy 2.450084 1.18364)
				(xy 2.450084 -2.999994) (xy -2.450084 -2.999994) (xy -2.450084 2.999994) (xy 2.450084 2.999994)
				(xy 2.450084 1.18618) (xy 2.8194 1.18618) (xy 2.8194 3.6322)
			)
			(stroke
				(width 0)
				(type default)
			)
			(fill no)
			(layer "F.CrtYd")
		)
		(fp_rect
			(start -2.8194 3.6322)
			(end 2.8194 -3.6322)
			(stroke
				(width 0)
				(type default)
			)
			(fill no)
			(layer "F.Fab")
		)
		(pad "1" smd rect
			(at -1.905 2.54 180)
			(size 0.635 1.651)
			(layers "F.Cu" "F.Mask" "F.Paste")
			(net "HB_A_OUT_EXP")
		)
		(pad "2" smd rect
			(at -0.635 2.54 180)
			(size 0.635 1.651)
			(layers "F.Cu" "F.Mask" "F.Paste")
			(net "HB_A_IN_EXP")
		)
		(pad "3" smd rect
			(at 0.635 2.54 180)
			(size 0.635 1.651)
			(layers "F.Cu" "F.Mask" "F.Paste")
			(net "DIVIDER 1_IN_EXP")
		)
		(pad "4" smd rect
			(at 1.905 2.54 180)
			(size 0.635 1.651)
			(layers "F.Cu" "F.Mask" "F.Paste")
			(net "GND")
		)
		(pad "5" smd rect
			(at 1.905 -2.54 180)
			(size 0.635 1.651)
			(layers "F.Cu" "F.Mask" "F.Paste")
			(net "HB_A_IN_EXP")
		)
		(pad "6" smd rect
			(at 0.635 -2.54 180)
			(size 0.635 1.651)
			(layers "F.Cu" "F.Mask" "F.Paste")
			(net "DIVIDER 2_IN_EXP")
		)
		(pad "7" smd rect
			(at -0.635 -2.54 180)
			(size 0.635 1.651)
			(layers "F.Cu" "F.Mask" "F.Paste")
			(net "HB_A_OUT_EXP")
		)
		(pad "8" smd rect
			(at -1.905 -2.54 180)
			(size 0.635 1.651)
			(layers "F.Cu" "F.Mask" "F.Paste")
			(net "P3V3_STBY")
		)
	)
	(footprint ""
		(layer "F.Cu")
		(at 145.034 -38.862)
		(property "Reference" "SR701"
			(at 0 0 0)
			(layer "F.SilkS")
			(hide yes)
			(effects
				(font
					(size 1.27 1.27)
				)
			)
		)
		(property "Value" "10KR2F-2-GP"
			(at 0.064008 -3.993896 0)
			(unlocked yes)
			(layer "F.Fab")
			(hide yes)
			(effects
				(font
					(size 1.016 1.016)
					(thickness 0.1524)
				)
			)
		)
		(property "Device Type" "R402H16"
			(at 0.064008 -5.517896 0)
			(unlocked yes)
			(layer "F.Fab")
			(hide yes)
			(effects
				(font
					(size 1.016 1.016)
					(thickness 0.1524)
				)
			)
		)
		(duplicate_pad_numbers_are_jumpers no)
		(fp_line
			(start -0.508 -0.9398)
			(end -0.508 0.9398)
			(stroke
				(width 0.1524)
				(type default)
			)
			(layer "F.SilkS")
		)
		(fp_line
			(start 0.508 -0.9398)
			(end -0.508 -0.9398)
			(stroke
				(width 0.1524)
				(type default)
			)
			(layer "F.SilkS")
		)
		(fp_rect
			(start -0.508 0.9398)
			(end 0.508 -0.9398)
			(stroke
				(width 0)
				(type default)
			)
			(fill no)
			(layer "F.CrtYd")
		)
		(fp_rect
			(start -0.508 0.9398)
			(end 0.508 -0.9398)
			(stroke
				(width 0)
				(type default)
			)
			(fill no)
			(layer "F.Fab")
		)
		(pad "1" smd custom
			(at 0 -0.4445)
			(size 0.1397 0.1397)
			(layers "F.Cu" "F.Mask" "F.Paste")
			(net "XM_ADDR_8")
			(options
				(clearance outline)
				(anchor circle)
			)
			(primitives
				(gr_poly
					(pts
						(arc
							(start -0.1778 -0.2794)
							(mid -0.249642 -0.249642)
							(end -0.2794 -0.1778)
						)
						(arc
							(start -0.2794 0.1778)
							(mid -0.249642 0.249642)
							(end -0.1778 0.2794)
						)
						(arc
							(start 0.1778 0.2794)
							(mid 0.249642 0.249642)
							(end 0.2794 0.1778)
						)
						(arc
							(start 0.2794 -0.1778)
							(mid 0.249642 -0.249642)
							(end 0.1778 -0.2794)
						)
					)
					(width 0)
					(fill yes)
				)
			)
		)
		(pad "2" smd custom
			(at 0 0.4445)
			(size 0.1397 0.1397)
			(layers "F.Cu" "F.Mask" "F.Paste")
			(net "GND")
			(options
				(clearance outline)
				(anchor circle)
			)
			(primitives
				(gr_poly
					(pts
						(arc
							(start -0.1778 -0.2794)
							(mid -0.249642 -0.249642)
							(end -0.2794 -0.1778)
						)
						(arc
							(start -0.2794 0.1778)
							(mid -0.249642 0.249642)
							(end -0.1778 0.2794)
						)
						(arc
							(start 0.1778 0.2794)
							(mid 0.249642 0.249642)
							(end 0.2794 0.1778)
						)
						(arc
							(start 0.2794 -0.1778)
							(mid 0.249642 -0.249642)
							(end 0.1778 -0.2794)
						)
					)
					(width 0)
					(fill yes)
				)
			)
		)
	)
)
